FILE_TYPE = CONNECTIVITY;
{Allegro Design Entry HDL 16.6-p007 (v16-6-112F) 10/10/2012}
"PAGE_NUMBER" = 232;
0"NC";
1"PVPP_DEF\g";
2"GND\g";
3"GND\g";
4"AGND_PVPP_DEF\g";
5"PVPP_DEF\g";
6"GND\g";
7"P12V_STBY\g";
8"GND\g";
9"GND\g";
10"P3V3_STBY\g";
11"GND\g";
12"GND\g";
13"GND\g";
14"GND\g";
15"GND\g";
16"GND\g";
17"AGND_PVPP_DEF\g";
18"AGND_PVPP_DEF\g";
19"AGND_PVPP_DEF\g";
20"AGND_PVPP_DEF\g";
21"AGND_PVPP_DEF\g";
22"AGND_PVPP_DEF\g";
23"GND\g";
24"GND\g";
25"GND\g";
26"GND\g";
27"GND\g";
28"AGND_PVPP_DEF\g";
29"VR_PVPP_DEF_PHASE";
30"VSENSE_PVPP_DEF";
31"VR_COMP_PVPP_DEF";
32"VR_FB_PVPP_DEF";
33"VR_PVPP_DEF_SNUB";
34"VR_COMP_PVPP_DEF_3";
35"VR_COMP_RC_PVPP_DEF";
36"VR_PVPP_DEF_BOOT";
37"PWRGD_PVPP_DEF";
38"PWRGD_PVPP_DEF_R";
39"VR_PVPP_DEF_BOOT_R";
40"VR_FET_SW_P12V_STBY_PVPP_DEF";
41"VR_PVPP_DEF_ISET";
42"VR_VB_PVPP_DEF";
43"VR_PVPP_DEF_SS";
44"FM_PVPP_PVDDQ_CPU0_EN_DEF";
45"FM_PVPP_CPU0_EN";
%"CAP"
"1","(-8550,875)","0","mstr_discrete","I102";
;
BOM_COST"MEM_VRD_PVPP_AB"
CDS_SEC"1"
$SEC"1"
ROOM"PVPP_KLM_VR"
CDS_LOCATION"C4L2"
CDS_LIB"mstr_discrete"
VOLTAGE"4V"
LOCATION"C4L2"
PART_NUMBER"E15431-001"
VALUE"10UF"
TOLERANCE"20%"
PACK_TYPE"0603LF"
MATERIAL"X6S";
"A"
$PN"1"1;
"B"
$PN"2"2;
%"PVPP_DEF"
"1","(-8550,1150)","0","mstr_symbols","I103";
;
ROOM"PVPP_KLM_VR"
BOM_COST"MEM_VRD_PVPP_AB"
HDL_POWER"PVPP_DEF"
CDS_LIB"mstr_symbols"
BODY_TYPE"PLUMBING"
VOLTAGE"2.5V";
"G\NAC"1;
%"CAP"
"1","(-8300,875)","0","mstr_discrete","I104";
;
ROOM"PVPP_KLM_VR"
$SEC"1"
CDS_SEC"1"
BOM_COST"MEM_VRD_PVPP_AB"
CDS_LOCATION"C6A3"
CDS_LIB"mstr_discrete"
VOLTAGE"4V"
LOCATION"C6A3"
PART_NUMBER"E15431-001"
VALUE"10UF"
TOLERANCE"20%"
PACK_TYPE"0603LF"
MATERIAL"X6S";
"A"
$PN"1"1;
"B"
$PN"2"2;
%"CAP"
"1","(-8025,875)","0","mstr_discrete","I105";
;
ROOM"PVPP_KLM_VR"
$SEC"1"
CDS_SEC"1"
BOM_COST"MEM_VRD_PVPP_AB"
CDS_LOCATION"C6A2"
CDS_LIB"mstr_discrete"
VOLTAGE"4V"
LOCATION"C6A2"
PART_NUMBER"E15431-001"
VALUE"10UF"
TOLERANCE"20%"
PACK_TYPE"0603LF"
MATERIAL"X6S";
"A"
$PN"1"1;
"B"
$PN"2"2;
%"CAP"
"1","(-7775,850)","0","mstr_discrete","I106";
;
$SEC"1"
CDS_SEC"1"
BOM_COST"MEM_VRD_PVPP_AB"
ROOM"PVPP_KLM_VR"
CDS_LOCATION"C4L3"
CDS_LIB"mstr_discrete"
VOLTAGE"4V"
LOCATION"C4L3"
PART_NUMBER"E15431-001"
VALUE"10UF"
TOLERANCE"20%"
PACK_TYPE"0603LF"
MATERIAL"X6S";
"A"
$PN"1"1;
"B"
$PN"2"2;
%"CAP"
"1","(-7500,875)","0","mstr_discrete","I108";
;
ROOM"PVPP_KLM_VR"
$SEC"1"
CDS_SEC"1"
BOM_COST"MEM_VRD_PVPP_AB"
CDS_LOCATION"C4L4"
CDS_LIB"mstr_discrete"
VOLTAGE"4V"
PART_NUMBER"E15431-001"
LOCATION"C4L4"
VALUE"10UF"
TOLERANCE"20%"
PACK_TYPE"0603LF"
MATERIAL"X6S";
"A"
$PN"1"1;
"B"
$PN"2"2;
%"CAP"
"1","(-7200,875)","0","mstr_discrete","I109";
;
BOM_COST"MEM_VRD_PVPP_AB"
CDS_SEC"1"
$SEC"1"
ROOM"PVPP_KLM_VR"
CDS_LOCATION"C6A7"
VOLTAGE"4V"
CDS_LIB"mstr_discrete"
PART_NUMBER"E15431-001"
MATERIAL"X6S"
TOLERANCE"20%"
VALUE"10UF"
LOCATION"C6A7"
PACK_TYPE"0603LF";
"A"
$PN"1"1;
"B"
$PN"2"2;
%"CAP"
"1","(-6925,875)","0","mstr_discrete","I110";
;
BOM_COST"MEM_VRD_PVPP_AB"
CDS_SEC"1"
$SEC"1"
ROOM"PVPP_KLM_VR"
VOLTAGE"4V"
CDS_LOCATION"C6A6"
CDS_LIB"mstr_discrete"
PART_NUMBER"E15431-001"
LOCATION"C6A6"
VALUE"10UF"
TOLERANCE"20%"
PACK_TYPE"0603LF"
MATERIAL"X6S";
"A"
$PN"1"1;
"B"
$PN"2"2;
%"CAP"
"1","(-6625,875)","0","mstr_discrete","I111";
;
ROOM"PVPP_KLM_VR"
$SEC"1"
CDS_SEC"1"
BOM_COST"MEM_VRD_PVPP_AB"
CDS_LOCATION"C4M3"
CDS_LIB"mstr_discrete"
VOLTAGE"4V"
PART_NUMBER"E15431-001"
MATERIAL"X6S"
TOLERANCE"20%"
VALUE"10UF"
LOCATION"C4M3"
PACK_TYPE"0603LF";
"A"
$PN"1"1;
"B"
$PN"2"2;
%"CAP"
"1","(-6325,875)","0","mstr_discrete","I125";
;
ROOM"PVPP_KLM_VR"
$SEC"1"
CDS_SEC"1"
BOM_COST"MEM_VRD_PVPP_AB"
VOLTAGE"4V"
CDS_LIB"mstr_discrete"
CDS_LOCATION"C4M4"
PART_NUMBER"E15431-001"
PACK_TYPE"0603LF"
LOCATION"C4M4"
VALUE"10UF"
TOLERANCE"20%"
MATERIAL"X6S";
"A"
$PN"1"1;
"B"
$PN"2"2;
%"CAP"
"1","(-6050,850)","0","mstr_discrete","I126";
;
CDS_SEC"1"
$SEC"1"
BOM_COST"MEM_VRD_PVPP_AB"
ROOM"PVPP_KLM_VR"
CDS_LOCATION"C6B2"
CDS_LIB"mstr_discrete"
VOLTAGE"4V"
LOCATION"C6B2"
PART_NUMBER"E15431-001"
VALUE"10UF"
PACK_TYPE"0603LF"
TOLERANCE"20%"
MATERIAL"X6S";
"A"
$PN"1"1;
"B"
$PN"2"2;
%"GND"
"1","(-5600,550)","0","mstr_symbols","I127";
;
HDL_POWER"GND"
VOLTAGE"0"
CDS_LIB"mstr_symbols"
SIZE"1B"
BOM_COST"MEM_VRD_PVPP_AB"
BODY_TYPE"PLUMBING"
ROOM"PVPP_KLM_VR";
"A\NAC"2;
%"CAP"
"1","(-5775,850)","0","mstr_discrete","I128";
;
CDS_SEC"1"
$SEC"1"
BOM_COST"MEM_VRD_PVPP_AB"
ROOM"PVPP_KLM_VR"
CDS_LOCATION"C6B1"
CDS_LIB"mstr_discrete"
VOLTAGE"4V"
LOCATION"C6B1"
PART_NUMBER"E15431-001"
VALUE"10UF"
PACK_TYPE"0603LF"
TOLERANCE"20%"
MATERIAL"X6S";
"A"
$PN"1"1;
"B"
$PN"2"2;
%"CAP"
"1","(-5525,875)","0","mstr_discrete","I129";
;
CDS_SEC"1"
BOM_COST"MEM_VRD_PVPP_AB"
SEC_TYPE"0603LF"
SEC"1"
ROOM"PVPP_KLM_VR"
VOLTAGE"4V"
CDS_LIB"mstr_discrete"
CDS_LOCATION"C4L1"
LOCATION"C4L1"
PART_NUMBER"E15431-001"
VALUE"10UF"
PACK_TYPE"0603LF"
TOLERANCE"20%"
MATERIAL"X6S";
"A"
$PN"1"1;
"B"
$PN"2"2;
%"GND"
"1","(-1875,675)","0","mstr_symbols","I149";
;
HDL_POWER"GND"
BODY_TYPE"PLUMBING"
SIZE"1B"
CDS_LIB"mstr_symbols"
VOLTAGE"0"
ROOM"PVPP_KLM_VR"
BOM_COST"PVPP_KLM_VR";
"A\NAC"3;
%"RES"
"1","(-1575,775)","0","mstr_discrete","I150";
;
CDS_LOCATION"R7B20"
ROOM"PVPP_KLM_VR"
$SEC"1"
CDS_SEC"1"
CDS_LIB"mstr_discrete"
LOCATION"R7B20"
PART_NUMBER"G21497-005"
TOLERANCE"5%"
PACK_TYPE"0402"
MATERIAL"CHIP"
WATTAGE"1/16W"
VALUE"0.0";
"B"
$PN"2"4;
"A"
$PN"1"3;
%"AGND_SCSI"
"1","(-1325,675)","0","mstr_symbols","I151";
;
ROOM"PVPP_KLM_VR"
CDS_LIB"mstr_symbols"
BOM_COST"PVPP_KLM_VR"
VOLTAGE"0.0V"
BODY_TYPE"PLUMBING"
HDL_POWER"AGND_PVPP_DEF";
"A"4;
%"PVPP_DEF"
"1","(-1150,3975)","0","mstr_symbols","I167";
;
BOM_COST"PVPP_KLM_VR"
ROOM"PVPP_KLM_VR"
HDL_POWER"PVPP_DEF"
CDS_LIB"mstr_symbols"
BODY_TYPE"PLUMBING"
VOLTAGE"2.5V";
"G\NAC"5;
%"CAP"
"1","(-6825,2500)","2","mstr_discrete","I185";
;
FIN"VR_1P2"
REUSE_ID"1"
CDS_SEC"1"
$SEC"1"
CDS_LOCATION"C7B9"
CDS_LIB"mstr_discrete"
BOM_COST"PVPP_KLM_VR"
ROOM"PVPP_KLM_VR"
LOCATION"C7B9"
VALUE"1000PF"
MATERIAL"EMPTY"
PART_NUMBER"A36096-046"
TOLERANCE"10%"
PACK_TYPE"0402LF"
VOLTAGE"50V";
"A"
$PN"1"45;
"B"
$PN"2"21;
%"RES"
"2","(-5100,1650)","2","mstr_discrete","I193";
;
CDS_SEC"1"
ROOM"PVPP_KLM_VR"
CDS_LIB"mstr_discrete"
BOM_COST"PVPP_KLM_VR"
$SEC"1"
CDS_LOCATION"R7B14"
LOCATION"R7B14"
VALUE"7.87K"
TOLERANCE"1.0%"
MATERIAL"CHIP"
WATTAGE"1/16W"
PART_NUMBER"G21796-242"
PACK_TYPE"0402";
"A"
$PN"1"41;
"B"
$PN"2"20;
%"CAP"
"1","(-5425,2175)","0","mstr_discrete","I197";
;
CDS_SEC"1"
SEC_TYPE"0402"
REUSE_ID"26"
BOM_COST"PVPP_KLM_VR"
SEC"1"
CDS_LOCATION"C7B11"
ROOM"PVPP_KLM_VR"
CDS_LIB"mstr_discrete"
LOCATION"C7B11"
VALUE"0.027UF"
TOLERANCE"10%"
PACK_TYPE"0402"
VOLTAGE"16V"
PART_NUMBER"A36096-129"
MATERIAL"X7R";
"A"
$PN"1"43;
"B"
$PN"2"18;
%"GND"
"1","(-5300,3825)","0","mstr_symbols","I198";
;
HDL_POWER"GND"
CDS_LIB"mstr_symbols"
VOLTAGE"0"
SIZE"1B"
BODY_TYPE"PLUMBING"
ROOM"PVPP_KLM_VR"
BOM_COST"PVPP_KLM_VR";
"A\NAC"6;
%"P12V_STBY"
"1","(-7950,4500)","0","mstr_symbols","I199";
;
SIZE"1B"
VOLTAGE"12.0V"
CDS_LIB"mstr_symbols"
BODY_TYPE"PLUMBING"
HDL_POWER"P12V_STBY";
"G\NAC"7;
%"FERRITE"
"1","(-7725,4300)","0","mstr_discrete","I200";
;
CDS_SEC"1"
ROOM"PVPP_KLM_VR"
CDS_LOCATION"FB7B1"
SEC"1"
SEC_TYPE"SM"
TOLERANCE"1%"
CDS_LIB"mstr_discrete"
PACK_TYPE"SM"
LOCATION"FB7B1"
PART_NUMBER"656554-051"
MATERIAL"FB"
VALUE"22";
"A"
$PN"1"7;
"B"
$PN"2"40;
%"GND"
"1","(-7375,3900)","0","mstr_symbols","I201";
;
HDL_POWER"GND"
BODY_TYPE"PLUMBING"
CDS_LIB"mstr_symbols"
SIZE"1B"
VOLTAGE"0"
ROOM"PVPP_KLM_VR"
BOM_COST"PVPP_KLM_VR";
"A\NAC"8;
%"CAP"
"1","(-7375,4125)","0","mstr_discrete","I202";
;
$SEC"1"
CDS_SEC"1"
CDS_LOCATION"C7B8"
ROOM"PVPP_KLM_VR"
BOM_COST"PVPP_KLM_VR"
CDS_LIB"mstr_discrete"
LOCATION"C7B8"
VALUE"47UF"
VOLTAGE"16V"
TOLERANCE"20%"
PART_NUMBER"D38464-007"
MATERIAL"X6S"
PACK_TYPE"1210";
"A"
$PN"1"40;
"B"
$PN"2"8;
%"CAP"
"1","(-5300,4150)","0","mstr_discrete","I207";
;
FIN"VR_1P2"
REUSE_ID"1"
$SEC"1"
CDS_SEC"1"
CDS_LOCATION"C3M9"
BOM_COST"PVPP_KLM_VR"
CDS_LIB"mstr_discrete"
ROOM"PVPP_KLM_VR"
VALUE"1.0UF"
TOLERANCE"10%"
VOLTAGE"16V"
LOCATION"C3M9"
PART_NUMBER"D97712-011"
MATERIAL"X6S"
PACK_TYPE"0402";
"A"
$PN"1"40;
"B"
$PN"2"6;
%"GND"
"1","(-4225,475)","0","mstr_symbols","I208";
;
HDL_POWER"GND"
CDS_LIB"mstr_symbols"
VOLTAGE"0"
SIZE"1B"
BODY_TYPE"PLUMBING"
ROOM"PVPP_KLM_VR"
BOM_COST"PVPP_KLM_VR";
"A\NAC"9;
%"CAP"
"1","(-4225,725)","0","mstr_discrete","I209";
;
REUSE_ID"17"
$SEC"1"
CDS_SEC"1"
CDS_LOCATION"C7B12"
CDS_LIB"mstr_discrete"
BOM_COST"PVPP_KLM_VR"
ROOM"PVPP_KLM_VR"
LOCATION"C7B12"
PART_NUMBER"A36096-046"
VALUE"1000PF"
TOLERANCE"10%"
PACK_TYPE"0402LF"
VOLTAGE"50V"
MATERIAL"X7R";
"A"
$PN"1"38;
"B"
$PN"2"9;
%"RES"
"2","(-4575,1250)","0","mstr_discrete","I210";
;
CDS_SEC"1"
REUSE_ID"21"
SEC_TYPE"0402"
BOM_COST"PVPP_KLM_VR"
SEC"1"
ROOM"PVPP_KLM_VR"
CDS_LOCATION"R7B17"
CDS_LIB"mstr_discrete"
PART_NUMBER"G21796-026"
LOCATION"R7B17"
VALUE"1.00K"
TOLERANCE"1%"
PACK_TYPE"0402"
MATERIAL"CHIP"
WATTAGE"1/16W";
"A"
$PN"1"10;
"B"
$PN"2"38;
%"P3V3_STBY"
"1","(-4575,1525)","0","mstr_symbols","I211";
;
VOLTAGE"+3.3V"
SIZE"1B"
CDS_LIB"mstr_symbols"
BODY_TYPE"PLUMBING"
HDL_POWER"P3V3_STBY";
"G\NAC"10;
%"NCP3232L"
"1","(-4150,2875)","0","mstr_vreg","I214";
;
CDS_SEC"1"
CDS_LOCATION"EU7B1"
SEC"1"
SEC_TYPE"SM"
PACK_TYPE"SM"
CDS_LMAN_SYM_OUTLINE"-450,850,450,-900"
CDS_LIB"mstr_vreg"
MATERIAL"IC"
LOCATION"EU7B1"
PART_NUMBER"H86355-001";
"PG"
$PN"7"38;
"PGND<0>"
$PN"16"11;
"PGND<1>"
$PN"17"11;
"PGND<2>"
$PN"18"11;
"PGND<3>"
$PN"19"11;
"PGND<4>"
$PN"20"11;
"PGND<5>"
$PN"21"11;
"PGND<6>"
$PN"22"11;
"PGND<8>"
$PN"24"11;
"PGND<7>"
$PN"23"11;
"PGND<9>"
$PN"25"11;
"PGND<10>"
$PN"26"11;
"PGND<11>"
$PN"27"11;
"PGND<12>"
$PN"28"11;
"PGND<13>"
$PN"37"11;
"GND"
$PN"41"11;
"AGND"
$PN"5"19;
"EN"
$PN"40"44;
"SS"
$PN"1"43;
"ISET"
$PN"4"41;
"OTS"
$PN"6"22;
"VIN<6>"
$PN"14"40;
"VIN<7>"
$PN"42"40;
"VCC"
$PN"39"40;
"VIN<1>"
$PN"9"40;
"VIN<5>"
$PN"13"40;
"VIN<4>"
$PN"12"40;
"VIN<3>"
$PN"11"40;
"VIN<2>"
$PN"10"40;
"VIN<0>"
$PN"8"40;
"VB"
$PN"38"42;
"COMP"
$PN"3"34;
"FB"
$PN"2"32;
"VSWH<1>"
$PN"29"29;
"VSWH<0>"
$PN"15"29;
"VSW"
$PN"35"29;
"VSWH<2>"
$PN"30"29;
"VSWH<3>"
$PN"31"29;
"VSWH<4>"
$PN"32"29;
"VSWH<5>"
$PN"33"29;
"VSWH<6>"
$PN"34"29;
"BST"
$PN"36"36;
"VSWH<7>"
$PN"43"29;
%"GND"
"1","(-3425,1925)","0","mstr_symbols","I215";
;
HDL_POWER"GND"
ROOM"PVPP_KLM_VR"
SIZE"1B"
VOLTAGE"0"
CDS_LIB"mstr_symbols"
BODY_TYPE"PLUMBING"
BOM_COST"PVPP_KLM_VR";
"A\NAC"11;
%"RES"
"2","(-3000,3350)","0","mstr_discrete","I218";
;
CDS_SEC"1"
SEC_TYPE"0402"
REUSE_ID"29"
SEC"1"
BOM_COST"PVPP_KLM_VR"
ROOM"PVPP_KLM_VR"
CDS_LOCATION"R7A15"
CDS_LIB"mstr_discrete"
MATERIAL"EMPTY"
LOCATION"R7A15"
PART_NUMBER"G21497-016"
VALUE"2.2"
PACK_TYPE"0402"
WATTAGE"1/16W"
TOLERANCE"5%";
"A"
$PN"1"33;
"B"
$PN"2"12;
%"GND"
"1","(-3000,3150)","0","mstr_symbols","I219";
;
HDL_POWER"GND"
SIZE"1B"
VOLTAGE"0"
CDS_LIB"mstr_symbols"
BODY_TYPE"PLUMBING"
ROOM"PVPP_KLM_VR"
BOM_COST"PVPP_KLM_VR";
"A\NAC"12;
%"CAP"
"1","(-3000,3700)","0","mstr_discrete","I220";
;
CDS_SEC"1"
SEC_TYPE"0402LF"
REUSE_ID"26"
BOM_COST"PVPP_KLM_VR"
SEC"1"
ROOM"PVPP_KLM_VR"
CDS_LOCATION"C7A34"
CDS_LIB"mstr_discrete"
MATERIAL"EMPTY"
LOCATION"C7A34"
VALUE"3300PF"
TOLERANCE"10%"
PACK_TYPE"0402LF"
VOLTAGE"50V"
PART_NUMBER"A36096-091";
"A"
$PN"1"29;
"B"
$PN"2"33;
%"GND"
"1","(-2425,3425)","0","mstr_symbols","I226";
;
HDL_POWER"GND"
VOLTAGE"0"
CDS_LIB"mstr_symbols"
SIZE"1B"
BODY_TYPE"PLUMBING"
ROOM"PVPP_KLM_VR"
BOM_COST"PVPP_KLM_VR";
"A\NAC"13;
%"RES"
"2","(-2425,3675)","0","mstr_discrete","I227";
;
CDS_SEC"1"
BOM_COST"PVPP_KLM_VR"
REUSE_ID"34"
SEC"1"
SEC_TYPE"0603"
ROOM"PVPP_KLM_VR"
CDS_LIB"mstr_discrete"
CDS_LOCATION"R7B10"
LOCATION"R7B10"
VALUE"120.0"
MATERIAL"CHIP"
WATTAGE"1/10W"
TOLERANCE"1%"
PART_NUMBER"G22026-003"
PACK_TYPE"0603";
"A"
$PN"1"5;
"B"
$PN"2"13;
%"GND"
"1","(-2075,3375)","0","mstr_symbols","I228";
;
SIZE"1B"
HDL_POWER"GND"
BODY_TYPE"PLUMBING"
VOLTAGE"0"
CDS_LIB"mstr_symbols"
ROOM"PVPP_KLM_VR"
BOM_COST"PVPP_KLM_VR";
"A\NAC"14;
%"CAPP"
"1","(-2075,3675)","0","mstr_discrete","I229";
;
REUSE_ID"28"
CDS_SEC"1"
$SEC"1"
CDS_LOCATION"C6B7"
CDS_LIB"mstr_discrete"
ROOM"PVPP_KLM_VR"
BOM_COST"PVPP_KLM_VR"
LOCATION"C6B7"
VALUE"330UF"
VOLTAGE"6.3V"
TOLERANCE"20%"
MATERIAL"POSCAP"
PACK_TYPE"7343LF"
PART_NUMBER"724613-042";
"B"
$PN"2"14;
"A"
$PN"1"5;
%"GND"
"1","(-1475,3425)","0","mstr_symbols","I235";
;
HDL_POWER"GND"
SIZE"1B"
VOLTAGE"0"
CDS_LIB"mstr_symbols"
BODY_TYPE"PLUMBING"
ROOM"PVPP_KLM_VR"
BOM_COST"PVPP_KLM_VR";
"A\NAC"15;
%"CAP"
"1","(-1475,3675)","0","mstr_discrete","I236";
;
REUSE_ID"33"
CDS_SEC"1"
$SEC"1"
CDS_LOCATION"C6B3"
CDS_LIB"mstr_discrete"
BOM_COST"PVPP_KLM_VR"
ROOM"PVPP_KLM_VR"
TOLERANCE"20%"
VALUE"47UF"
LOCATION"C6B3"
VOLTAGE"4V"
MATERIAL"X6S"
PART_NUMBER"C95333-006"
PACK_TYPE"0805";
"A"
$PN"1"5;
"B"
$PN"2"15;
%"GND"
"1","(-1200,3400)","0","mstr_symbols","I237";
;
HDL_POWER"GND"
SIZE"1B"
VOLTAGE"0"
CDS_LIB"mstr_symbols"
BODY_TYPE"PLUMBING"
ROOM"PVPP_KLM_VR"
BOM_COST"PVPP_KLM_VR";
"A\NAC"16;
%"CAP"
"1","(-1200,3675)","0","mstr_discrete","I238";
;
REUSE_ID"33"
CDS_SEC"1"
$SEC"1"
BOM_COST"PVPP_KLM_VR"
CDS_LIB"mstr_discrete"
CDS_LOCATION"C7B7"
ROOM"PVPP_KLM_VR"
PART_NUMBER"C95333-006"
LOCATION"C7B7"
VALUE"47UF"
TOLERANCE"20%"
VOLTAGE"4V"
MATERIAL"X6S"
PACK_TYPE"0805";
"A"
$PN"1"5;
"B"
$PN"2"16;
%"INDUCTOR"
"1","(-2650,3850)","0","mstr_discrete","I239";
;
CDS_LIB"mstr_discrete"
BOM_COST"PVPP_KLM_VR"
ROOM"PVPP_KLM_VR"
TOLERANCE"1%"
REUSE_ID"30"
CDS_SEC"1"
$SEC"1"
CDS_LOCATION"L7B1"
PACK_TYPE"SM"
PART_NUMBER"E13358-018"
LOCATION"L7B1"
MATERIAL"IND"
VALUE"0.47UH";
"INA\NAC"
$PN"1"29;
"INB\NAC"
$PN"2"5;
%"RES"
"1","(-4425,4200)","0","mstr_discrete","I240";
;
CDS_LOCATION"R7B19"
REUSE_ID"13"
$SEC"1"
CDS_SEC"1"
SPOF"TRUE"
ROOM"PVPP_KLM_VR"
BOM_COST"PVPP_KLM_VR"
CDS_LIB"mstr_discrete"
PART_NUMBER"G21497-005"
LOCATION"R7B19"
VALUE"0.0"
TOLERANCE"5%"
PACK_TYPE"0402"
WATTAGE"1/16W"
MATERIAL"CHIP";
"B"
$PN"2"39;
"A"
$PN"1"36;
%"CAP"
"2","(-3725,4200)","2","mstr_discrete","I241";
;
CDS_LOCATION"C7B30"
BOM_COST"PVPP_KLM_VR"
$SEC"1"
CDS_SEC"1"
SPOF"TRUE"
REUSE_ID"27"
ROOM"PVPP_KLM_VR"
CDS_LIB"mstr_discrete"
PART_NUMBER"602433-020"
VALUE"0.1UF"
VOLTAGE"25V"
LOCATION"C7B30"
TOLERANCE"10%"
PACK_TYPE"0603LF"
MATERIAL"X7R";
"A"
$PN"1"29;
"B"
$PN"2"39;
%"AGND_SCSI"
"1","(-6125,2025)","0","mstr_symbols","I247";
;
CDS_LIB"mstr_symbols"
VOLTAGE"0.0V"
BOM_COST"PVPP_KLM_VR"
BODY_TYPE"PLUMBING"
ROOM"PVPP_KLM_VR"
HDL_POWER"AGND_PVPP_DEF";
"A"17;
%"AGND_SCSI"
"1","(-5425,1950)","0","mstr_symbols","I248";
;
BOM_COST"PVPP_KLM_VR"
VOLTAGE"0.0V"
CDS_LIB"mstr_symbols"
BODY_TYPE"PLUMBING"
ROOM"PVPP_KLM_VR"
HDL_POWER"AGND_PVPP_DEF";
"A"18;
%"AGND_SCSI"
"1","(-4725,1850)","0","mstr_symbols","I249";
;
CDS_LIB"mstr_symbols"
VOLTAGE"0.0V"
BODY_TYPE"PLUMBING"
ROOM"PVPP_KLM_VR"
BOM_COST"PVPP_KLM_VR"
HDL_POWER"AGND_PVPP_DEF";
"A"19;
%"AGND_SCSI"
"1","(-5100,1350)","0","mstr_symbols","I250";
;
VOLTAGE"0"
CDS_LIB"mstr_symbols"
BODY_TYPE"PLUMBING"
HDL_POWER"AGND_PVPP_DEF";
"A"20;
%"AGND_SCSI"
"1","(-6825,2125)","0","mstr_symbols","I251";
;
VOLTAGE"0.0V"
CDS_LIB"mstr_symbols"
BODY_TYPE"PLUMBING"
BOM_COST"PVPP_KLM_VR"
ROOM"PVPP_KLM_VR"
HDL_POWER"AGND_PVPP_DEF";
"A"21;
%"CAP_A"
"1","(-5475,3525)","0","dev_discrete","I252";
;
SEC"1"
SEC_TYPE"0402V"
CDS_SEC"1"
CDS_LOCATION"C7B6"
CDS_LIB"dev_discrete"
LOCATION"C7B6"
VALUE"0.1UF"
PART_NUMBER"A36096-030"
TOLERANCE"10%"
PACK_TYPE"0402V"
VOLTAGE"16V"
MATERIAL"X7R";
"B"
$PN"2"23;
"A"
$PN"1"40;
%"CAP"
"1","(-6125,2425)","0","mstr_discrete","I253";
;
CDS_SEC"1"
REUSE_ID"26"
SEC_TYPE"0603"
BOM_COST"PVPP_KLM_VR"
SEC"1"
ROOM"PVPP_KLM_VR"
CDS_LIB"mstr_discrete"
CDS_LOCATION"C3M10"
PART_NUMBER"E15431-003"
VALUE"4.7UF"
TOLERANCE"10%"
PACK_TYPE"0603"
VOLTAGE"6.3V"
LOCATION"C3M10"
MATERIAL"X6S";
"A"
$PN"1"42;
"B"
$PN"2"17;
%"AGND_SCSI"
"1","(-5775,2725)","0","mstr_symbols","I254";
;
BODY_TYPE"PLUMBING"
CDS_LIB"mstr_symbols"
VOLTAGE"0.0V"
ROOM"PVPP_KLM_VR"
BOM_COST"PVPP_KLM_VR"
HDL_POWER"AGND_PVPP_DEF";
"A"22;
%"GND"
"1","(-5475,3275)","0","mstr_symbols","I255";
;
HDL_POWER"GND"
VOLTAGE"0"
CDS_LIB"mstr_symbols"
SIZE"1B"
BODY_TYPE"PLUMBING"
ROOM"PVPP_KLM_VR"
BOM_COST"PVPP_KLM_VR";
"A\NAC"23;
%"RES"
"1","(-3875,975)","0","mstr_discrete","I257";
;
CDS_SEC"1"
ROOM"PVPP_DEF_VR"
CDS_LOCATION"R7B12"
SEC"1"
SEC_TYPE"0402"
CDS_LIB"mstr_discrete"
PART_NUMBER"G21796-250"
LOCATION"R7B12"
PACK_TYPE"0402"
MATERIAL"CHIP"
TOLERANCE"1.0%"
WATTAGE"1/16W"
VALUE"22.1";
"B"
$PN"2"37;
"A"
$PN"1"38;
%"CAP"
"1","(-6975,4100)","0","mstr_discrete","I259";
;
CDS_SEC"1"
SEC"1"
SEC_TYPE"0805"
CDS_LOCATION"C3M8"
CDS_LIB"mstr_discrete"
LOCATION"C3M8"
VALUE"10UF"
VOLTAGE"16V"
PART_NUMBER"C95333-007"
TOLERANCE"10%"
PACK_TYPE"0805"
MATERIAL"X6S";
"A"
$PN"1"40;
"B"
$PN"2"24;
%"CAP"
"1","(-6600,4100)","0","mstr_discrete","I260";
;
CDS_SEC"1"
SEC"1"
SEC_TYPE"0805"
CDS_LOCATION"C3M15"
CDS_LIB"mstr_discrete"
LOCATION"C3M15"
VALUE"10UF"
VOLTAGE"16V"
PART_NUMBER"C95333-007"
TOLERANCE"10%"
PACK_TYPE"0805"
MATERIAL"X6S";
"A"
$PN"1"40;
"B"
$PN"2"25;
%"CAP"
"1","(-6225,4100)","0","mstr_discrete","I261";
;
CDS_SEC"1"
SEC"1"
SEC_TYPE"0805"
CDS_LOCATION"C3M16"
CDS_LIB"mstr_discrete"
LOCATION"C3M16"
VALUE"10UF"
VOLTAGE"16V"
PART_NUMBER"C95333-007"
TOLERANCE"10%"
PACK_TYPE"0805"
MATERIAL"X6S";
"A"
$PN"1"40;
"B"
$PN"2"26;
%"CAP"
"1","(-5850,4100)","0","mstr_discrete","I262";
;
CDS_SEC"1"
SEC"1"
SEC_TYPE"0805"
CDS_LOCATION"C7B5"
CDS_LIB"mstr_discrete"
LOCATION"C7B5"
VALUE"10UF"
VOLTAGE"16V"
PART_NUMBER"C95333-007"
TOLERANCE"10%"
PACK_TYPE"0805"
MATERIAL"X6S";
"A"
$PN"1"40;
"B"
$PN"2"27;
%"GND"
"1","(-6975,3900)","0","mstr_symbols","I263";
;
SIZE"1B"
HDL_POWER"GND"
BODY_TYPE"PLUMBING"
CDS_LIB"mstr_symbols"
VOLTAGE"0"
ROOM"PVPP_KLM_VR"
BOM_COST"PVPP_KLM_VR";
"A\NAC"24;
%"GND"
"1","(-6600,3900)","0","mstr_symbols","I264";
;
SIZE"1B"
HDL_POWER"GND"
BODY_TYPE"PLUMBING"
CDS_LIB"mstr_symbols"
VOLTAGE"0"
ROOM"PVPP_KLM_VR"
BOM_COST"PVPP_KLM_VR";
"A\NAC"25;
%"GND"
"1","(-6225,3900)","0","mstr_symbols","I265";
;
HDL_POWER"GND"
BODY_TYPE"PLUMBING"
SIZE"1B"
CDS_LIB"mstr_symbols"
VOLTAGE"0"
ROOM"PVPP_KLM_VR"
BOM_COST"PVPP_KLM_VR";
"A\NAC"26;
%"GND"
"1","(-5850,3900)","0","mstr_symbols","I266";
;
HDL_POWER"GND"
SIZE"1B"
CDS_LIB"mstr_symbols"
VOLTAGE"0"
BODY_TYPE"PLUMBING"
ROOM"PVPP_KLM_VR"
BOM_COST"PVPP_KLM_VR";
"A\NAC"27;
%"CAPP"
"1","(-1800,3650)","0","mstr_discrete","I267";
;
CDS_SEC"1"
SEC_TYPE"7343"
SEC"1"
CDS_LOCATION"C4M1"
CDS_LIB"mstr_discrete"
PART_NUMBER"724613-067"
LOCATION"C4M1"
VALUE"220UF"
TOLERANCE"20%"
VOLTAGE"4V"
MATERIAL"POSCAP"
PACK_TYPE"7343";
"B"
$PN"2"14;
"A"
$PN"1"5;
%"RES"
"2","(-1375,2625)","0","mstr_discrete","I298";
;
CDS_SEC"1"
SEC_TYPE"0402"
SPOF"TRUE"
REUSE_ID"9"
SEC"1"
ROOM"PVPP_KLM_VR"
BOM_COST"PVPP_KLM_VR"
CDS_LOCATION"R7B18"
CDS_LIB"mstr_discrete"
LOCATION"R7B18"
VALUE"1.0K"
TOLERANCE"0.1%"
WATTAGE"1/16W"
PACK_TYPE"0402"
PART_NUMBER"G85996-004"
MATERIAL"CHIP";
"A"
$PN"1"30;
"B"
$PN"2"31;
%"RES"
"1","(-1700,2925)","5","mstr_discrete","I299";
;
CDS_SEC"1"
SEC"1"
SPOF"TRUE"
SEC_TYPE"0402"
ROOM"PVPP_KLM_VR"
CDS_LOCATION"R7B11"
CDS_LIB"mstr_discrete"
LOCATION"R7B11"
PART_NUMBER"G21497-005"
WATTAGE"1/16W"
VALUE"0.0"
MATERIAL"CHIP"
TOLERANCE"5%"
PACK_TYPE"0402";
"B"
$PN"2"30;
"A"
$PN"1"5;
%"RES"
"1","(-2500,2450)","0","mstr_discrete","I300";
;
CDS_SEC"1"
REUSE_ID"13"
SEC_TYPE"0402"
SEC"1"
ROOM"PVPP_KLM_VR"
CDS_LOCATION"R7B16"
CDS_LIB"mstr_discrete"
BOM_COST"PVPP_KLM_VR"
PACK_TYPE"0402"
LOCATION"R7B16"
TOLERANCE"1.0%"
MATERIAL"CHIP"
PART_NUMBER"G21796-242"
WATTAGE"1/16W"
VALUE"7.87K";
"B"
$PN"2"32;
"A"
$PN"1"35;
%"CAP"
"2","(-2775,2825)","2","mstr_discrete","I301";
;
CDS_SEC"1"
REUSE_ID"27"
SEC_TYPE"0402LF"
SEC"1"
ROOM"PVPP_KLM_VR"
CDS_LOCATION"C7B10"
CDS_LIB"mstr_discrete"
BOM_COST"PVPP_KLM_VR"
MATERIAL"COG"
TOLERANCE"5%"
VALUE"100.0PF"
LOCATION"C7B10"
VOLTAGE"50V"
PACK_TYPE"0402LF"
PART_NUMBER"A36095-026";
"A"
$PN"1"32;
"B"
$PN"2"34;
%"CAP"
"1","(-1375,2075)","0","mstr_discrete","I302";
;
CDS_SEC"1"
SPOF"TRUE"
SEC_TYPE"0402LF"
REUSE_ID"26"
ROOM"PVPP_KLM_VR"
CDS_LOCATION"C7B13"
BOM_COST"PVPP_KLM_VR"
CDS_LIB"mstr_discrete"
SEC"1"
LOCATION"C7B13"
VALUE"2200PF"
VOLTAGE"50V"
TOLERANCE"10%"
PART_NUMBER"A36096-075"
PACK_TYPE"0402LF"
MATERIAL"X7R";
"A"
$PN"1"31;
"B"
$PN"2"32;
%"RES"
"2","(-1700,2175)","0","mstr_discrete","I303";
;
$SEC"1"
BOM_COST"PVPP_KLM_VR"
REUSE_ID"9"
ROOM"PVPP_KLM_VR"
CDS_SEC"1"
SPOF"TRUE"
CDS_LOCATION"R7B15"
CDS_LIB"mstr_discrete"
LOCATION"R7B15"
VALUE"20.0K"
WATTAGE"1/16W"
TOLERANCE"1%"
PACK_TYPE"0402"
MATERIAL"CHIP"
PART_NUMBER"G21796-040";
"A"
$PN"1"30;
"B"
$PN"2"32;
%"RES"
"2","(-1700,1550)","0","mstr_discrete","I304";
;
CDS_SEC"1"
SPOF"TRUE"
REUSE_ID"7"
$SEC"1"
CDS_LOCATION"R7B13"
CDS_LIB"mstr_discrete"
ROOM"PVPP_KLM_VR"
BOM_COST"PVPP_KLM_VR"
LOCATION"R7B13"
PART_NUMBER"G21796-146"
VALUE"6.34K"
WATTAGE"1/16W"
TOLERANCE"1%"
PACK_TYPE"0402"
MATERIAL"CHIP";
"A"
$PN"1"32;
"B"
$PN"2"28;
%"CAP"
"2","(-3200,2450)","2","mstr_discrete","I306";
;
CDS_SEC"1"
ROOM"PVPP_KLM_VR"
SEC"1"
REUSE_ID"27"
BOM_COST"PVPP_KLM_VR"
SEC_TYPE"0402LF"
CDS_LOCATION"C7B14"
CDS_LIB"mstr_discrete"
PART_NUMBER"A36096-075"
VALUE"2200PF"
VOLTAGE"50V"
LOCATION"C7B14"
MATERIAL"X7R"
TOLERANCE"10%"
PACK_TYPE"0402LF";
"A"
$PN"1"35;
"B"
$PN"2"34;
%"RES"
"1","(-6500,2825)","0","mstr_discrete","I307";
;
CDS_SEC"1"
ROOM"PVCCIN_CPU0_VR"
CDS_LOCATION"R7B9"
SEC"1"
CDS_LIB"mstr_discrete"
SEC_TYPE"0402"
PART_NUMBER"G21497-005"
PACK_TYPE"0402"
MATERIAL"CHIP"
LOCATION"R7B9"
TOLERANCE"5%"
VALUE"0.0"
WATTAGE"1/16W";
"B"
$PN"2"44;
"A"
$PN"1"45;
%"AGND_SCSI"
"1","(-1700,1175)","0","mstr_symbols","I308";
;
CDS_LIB"mstr_symbols"
BODY_TYPE"PLUMBING"
VOLTAGE"0.0V"
ROOM"PVPP_KLM_VR"
BOM_COST"PVPP_KLM_VR"
HDL_POWER"AGND_PVPP_DEF";
"A"28;
END.
